# BASEBOARD_FAB2 (Tioga Pass) — schematic parts with pin connectivity, parts 2272–2283 of 4751; source: Cadence DE-HDL packaged netlist (pstxprt.dat, pstxnet.dat, pstchip.dat)

EU1G2  PXM1310B  IC  pkg QFN  page 223
  1  BPWM1  OUT  = NC
  2  DNC(0)  NC  = NC
  3  APWM3  OUT  = NC
  4  APWM2  OUT  = VR_PVDDQ_GHJ_PWM2
  5  APWM1  OUT  = VR_PVDDQ_GHJ_PWM1
  6  SDA  BI  = SMB_VR_STBY_LVC3_SDA
  7  SCL  BI  = SMB_VR_STBY_LVC3_SCL
  8  RESET_N  IN  = NC
  9  AVRRDY  OUT  = PWRGD_PVDDQ_GHJ_R
  10  AVREN  IN  = VR_PVDDQ_GHJ_VREN
  11  VRHOT_N  OUT  = IRQ_PVDDQ_GHJ_VRHOT_LVT3_R_N
  12  PINALRT_N  OUT  = NC
  13  MP0  BI  = PU_VR_PVDDQ_GHJ_FAULT1
  14  MP1  BI  = TP_PVDDQ_GHJ_MP1
  15  VCLK  IN  = SVID_CLK_PVDDQ_GHJ
  16  VDIO  BI  = SVID_VDIO_PVDDQ_GHJ
  17  VALRT_N  OUT  = SVID_ALERT_PVDDQ_GHJ
  18  MP2  BI  = TP_PVDDQ_GHJ_MP2
  19  AVSEN  IN  = VR_PVDDQ_GHJ_AVSP
  20  AVREF  IN  = VSENSE_PVDDQ_GHJ_N
  21  AIREF1  IN  = VR_PVDDQ_GHJ_AIREF1
  22  AISEN1  IN  = ISENSE_PVDDQ_GHJ_PH1_IMON
  23  AIREF2  IN  = VR_PVDDQ_GHJ_AIREF2
  24  AISEN2  IN  = ISENSE_PVDDQ_GHJ_PH2_IMON
  25  AIREF3  IN  = NC
  26  AISEN3  IN  = NC
  27  GND  GROUND  = GND
  28  DNC(1)  NC  = NC
  29  BVSEN  IN  = NC
  30  BVREF  IN  = NC
  31  BIREF1  IN  = NC
  32  BISEN1  IN  = GND
  33  XADDR2  IN  = VR_PVDDQ_GHJ_XADDR2
  34  BTSEN  IN  = NC
  35  ATSEN  IN  = A_TSENSE_PVDDQ_GHJ
  36  XADDR1  IN  = VR_PVDDQ_GHJ_XADDR1
  37  VINSEN  IN  = VR_PVDDQ_GHJ_VINSEN
  38  IINSEN  IN  = VR_PVDDQ_GHJ_AIINSEN
  39  VDD  POWER  = VR_PVDDQ_GHJ_VDD
  40  VD12  BI  = VR_PVDDQ_GHJ_VD12
  41  THPAD  GROUND  = GND

EU2T1  SLG55021  IC  pkg SM  page 198
  1  VCC  POWER  = P5V_STBY
  2  \on\  IN  = FM_P3V3_CPLD_EN
  3  SHDN_N  IN  = P5V_STBY
  4  GND  GROUND  = GND
  5  D  IN  = P3V3_STBY
  6  S  IN  = P3V3
  7  G  OUT  = P3V3_SWITCH_G
  8  PG  OUT  = TP_SLG55021_P3V3_8
  9  THPAD  GROUND  = GND

EU3P1  PXE1110B  IC  pkg QFN  page 211
  1  DNC(0)  NC  = NC
  2  DNC(1)  NC  = NC
  3  BPWM1  OUT  = NC
  4  DNC(2)  NC  = NC
  5  APWM1  OUT  = VR_PVCCIO_CPU0_PWM1
  6  SDA  BI  = SMB_VR_STBY_LVC3_SDA
  7  SCL  BI  = SMB_VR_STBY_LVC3_SCL
  8  RESET_N  IN  = NC
  9  AVRRDY  OUT  = PWRGD_PVCCIO_CPU0_R
  10  AVREN  IN  = VR_PVCCIO_CPU0_EN
  11  VRHOT_N  OUT  = IRQ_PVCCIO_CPU0_VRHOT_N
  12  PINALRT_N  OUT  = NC
  13  MP0  BI  = NC
  14  MP1  BI  = NC
  15  VCLK  IN  = SVID_CLK_PVCCIO_CPU0
  16  VDIO  BI  = SVID_VDIO_PVCCIO_CPU0
  17  VALRT_N  OUT  = SVID_ALERT_PVCCIO_CPU0
  18  MP2  OUT  = NC
  19  AVSEN  IN  = VR_PVCCIO_CPU0_AVSP
  20  AVREF  IN  = VSENSE_PVCCIO_CPU0_AVSN
  21  AIREF1  IN  = VR_PVCCIO_CPU0_AIREF1
  22  AISEN1  IN  = ISENSE_PVCCIO_CPU0_PH1_IMON
  23  GND(1)  GROUND  = GND
  24  DNC(3)  NC  = NC
  25  BIREF1  IN  = NC
  26  BISEN1  IN  = GND
  27  GND(0)  GROUND  = GND
  28  DNC(4)  NC  = NC
  29  BVSEN  IN  = NC
  30  BVREF  IN  = NC
  31  MP3  BI  = NC
  32  MP4  BI  = PU_VR_PVCCIO_CPU0_FAULT1
  33  XADDR2  IN  = VR_PVCCIO_CPU0_XADDR2
  34  BTSEN  IN  = NC
  35  ATSEN  IN  = A_TSENSE_PVCCIO_CPU0
  36  XADDR1  IN  = VR_PVCCIO_CPU0_XADDR1
  37  VINSEN  IN  = VR_PVCCIO_CPU0_VINSEN
  38  IINSEN  IN  = NC
  39  VDD  POWER  = VR_PVCCIO_CPU0_VDD
  40  VD12  POWER  = VR_PVCCIO_CPU0_VD12
  41  THPAD  GROUND  = GND

EU4A1  MIC5166  IC  pkg DFN  page 222
  1  VREF  OUT  = VR_PVTT_DEF_VREF
  2  BIAS  BI  = VR_PVTT_DEF_BIAS
  3  AGND  GROUND  = GND
  4  VDDQ  POWER  = VSENSE_PVDDQ_DEF_VTT
  5  PG  OUT  = PWRGD_PVTT_DEF_CPU0_R
  6  SNS  IN  = VR_PVTT_DEF_SNS
  7  EN  IN  = FM_PVTT_DEF_EN_R
  8  PGND  GROUND  = GND
  9  VTT  OUT  = PVTT_DEF
  10  VIN  POWER  = PVDDQ_DEF
  11  THPAD  GROUND  = GND

EU4A2  MIC5166  IC  pkg DFN  page 230
  1  VREF  OUT  = VR_PVTT_KLM_VREF
  2  BIAS  BI  = VR_PVTT_KLM_BIAS
  3  AGND  GROUND  = GND
  4  VDDQ  POWER  = VSENSE_PVDDQ_KLM_VTT
  5  PG  OUT  = PWRGD_PVTT_KLM_CPU1_R
  6  SNS  IN  = VR_PVTT_KLM_SNS
  7  EN  IN  = FM_PVTT_KLM_EN_R
  8  PGND  GROUND  = GND
  9  VTT  OUT  = PVTT_KLM
  10  VIN  POWER  = PVDDQ_KLM
  11  THPAD  GROUND  = GND

EU4A3  NCP3232L  IC  pkg SM  page 234
  1  SS  BI  = VR_PVPP_KLM_SS
  2  FB  BI  = VR_FB_PVPP_KLM
  3  COMP  OUT  = VR_COMP_PVPP_KLM_3
  4  ISET  BI  = VR_PVPP_KLM_ISET
  5  AGND  GROUND  = AGND_PVPP_KLM
  6  OTS  IN  = AGND_PVPP_KLM
  7  PG  BI  = PWRGD_PVPP_KLM_R
  8  VIN(0)  IN  = VR_FET_SW_P12V_STBY_PVPP_KLM
  9  VIN(1)  IN  = VR_FET_SW_P12V_STBY_PVPP_KLM
  10  VIN(2)  IN  = VR_FET_SW_P12V_STBY_PVPP_KLM
  11  VIN(3)  IN  = VR_FET_SW_P12V_STBY_PVPP_KLM
  12  VIN(4)  IN  = VR_FET_SW_P12V_STBY_PVPP_KLM
  13  VIN(5)  IN  = VR_FET_SW_P12V_STBY_PVPP_KLM
  14  VIN(6)  IN  = VR_FET_SW_P12V_STBY_PVPP_KLM
  15  VSWH(0)  BI  = VR_PVPP_KLM_PHASE
  16  PGND(0)  GROUND  = GND
  17  PGND(1)  GROUND  = GND
  18  PGND(2)  GROUND  = GND
  19  PGND(3)  GROUND  = GND
  20  PGND(4)  GROUND  = GND
  21  PGND(5)  GROUND  = GND
  22  PGND(6)  GROUND  = GND
  23  PGND(7)  GROUND  = GND
  24  PGND(8)  GROUND  = GND
  25  PGND(9)  GROUND  = GND
  26  PGND(10)  GROUND  = GND
  27  PGND(11)  GROUND  = GND
  28  PGND(12)  GROUND  = GND
  29  VSWH(1)  BI  = VR_PVPP_KLM_PHASE
  30  VSWH(2)  BI  = VR_PVPP_KLM_PHASE
  31  VSWH(3)  BI  = VR_PVPP_KLM_PHASE
  32  VSWH(4)  BI  = VR_PVPP_KLM_PHASE
  33  VSWH(5)  BI  = VR_PVPP_KLM_PHASE
  34  VSWH(6)  BI  = VR_PVPP_KLM_PHASE
  35  VSW  BI  = VR_PVPP_KLM_PHASE
  36  BST  IN  = VR_PVPP_KLM_BOOT
  37  PGND(13)  GROUND  = GND
  38  VB  OUT  = VR_VB_PVPP_KLM
  39  VCC  POWER  = VR_FET_SW_P12V_STBY_PVPP_KLM
  40  EN  IN  = FM_PVPP_PVDDQ_CPU1_EN_KLM
  41  GND  GROUND  = GND
  42  VIN(7)  IN  = VR_FET_SW_P12V_STBY_PVPP_KLM
  43  VSWH(7)  BI  = VR_PVPP_KLM_PHASE

EU4C1  IR354XX  IR35412 IC  pkg SM  page 205
  1  VOS  BI  = PVSA_CPU0
  2  LGND  GROUND  = GND
  3  VCC  POWER  = VR_PVSA_CPU0_VCIN
  4  VDRV  BI  = P5V_STBY
  5  PGND(0)  GROUND  = GND
  6  GL(0)  BI  = TP_PVSA_CPU0_GL_0
  7  PGND(1)  GROUND  = GND
  10  SW  BI  = VR_PVSA_CPU0_PHASE_SW
  25  VIN(0)  POWER  = VR_FET_SW_P12V_STBY_PVCCIN_CPU0
  30  VIN(1)  POWER  = VR_FET_SW_P12V_STBY_PVCCIN_CPU0
  31  NC  NC  = NC
  32  PHASE  BI  = VR_PVSA_CPU0_PHASE
  33  BOOST  BI  = VR_PVSA_CPU0_BOOT_R
  34  PWM  IN  = VR_PVSA_CPU0_PWM
  35  EN  BI  = P5V_STBY
  36  TOUT_FLT  BI  = A_TSENSE_PVSA_CPU0
  37  OCSET  BI  = VR_PVSA_CPU0_OCSET
  38  IOUT  OUT  = ISENSE_PVSA_CPU0_IMON
  39  REFIN  IN  = VR_PVSA_CPU0_BIREF1
  40  PGND(2)  GROUND  = GND
  41  GL(1)  BI  = TP_PVSA_CPU0_GL_1

EU4C2  IR354XX  IR35411 IC  pkg SM  page 204
  1  VOS  BI  = PVCCIN_CPU0
  2  LGND  GROUND  = GND
  3  VCC  POWER  = VR_PVCCIN_CPU0_PH5_VCIN
  4  VDRV  BI  = P5V_STBY
  5  PGND(0)  GROUND  = GND
  6  GL(0)  BI  = TP_PVCCIN_CPU0_PH5_GL_0
  7  PGND(1)  GROUND  = GND
  10  SW  BI  = VR_PVCCIN_CPU0_PHASE5
  25  VIN(0)  POWER  = VR_FET_SW_P12V_STBY_PVCCIN_CPU0
  30  VIN(1)  POWER  = VR_FET_SW_P12V_STBY_PVCCIN_CPU0
  31  NC  NC  = NC
  32  PHASE  BI  = VR_PVCCIN_CPU0_PH5_PHASE
  33  BOOST  BI  = VR_PVCCIN_CPU0_PH5_BOOT_R
  34  PWM  IN  = VR_PVCCIN_CPU0_PWM5
  35  EN  BI  = P5V_STBY
  36  TOUT_FLT  BI  = A_TSENSE_PVCCIN_CPU0
  37  OCSET  BI  = VR_PVCCIN_CPU0_PH5_OCSET
  38  IOUT  OUT  = ISENSE_PVCCIN_CPU0_PH5_IMON
  39  REFIN  IN  = VR_PVCCIN_CPU0_AIREF5
  40  PGND(2)  GROUND  = GND
  41  GL(1)  BI  = TP_PVCCIN_CPU0_PH5_GL_1

EU4D1  IR354XX  IR35411 IC  pkg SM  page 203
  1  VOS  BI  = PVCCIN_CPU0
  2  LGND  GROUND  = GND
  3  VCC  POWER  = VR_PVCCIN_CPU0_PH4_VCIN
  4  VDRV  BI  = P5V_STBY
  5  PGND(0)  GROUND  = GND
  6  GL(0)  BI  = TP_PVCCIN_CPU0_PH4_GL_0
  7  PGND(1)  GROUND  = GND
  10  SW  BI  = VR_PVCCIN_CPU0_PHASE4
  25  VIN(0)  POWER  = VR_FET_SW_P12V_STBY_PVCCIN_CPU0
  30  VIN(1)  POWER  = VR_FET_SW_P12V_STBY_PVCCIN_CPU0
  31  NC  NC  = NC
  32  PHASE  BI  = VR_PVCCIN_CPU0_PH4_PHASE
  33  BOOST  BI  = VR_PVCCIN_CPU0_PH4_BOOT_R
  34  PWM  IN  = VR_PVCCIN_CPU0_PWM4
  35  EN  BI  = P5V_STBY
  36  TOUT_FLT  BI  = A_TSENSE_PVCCIN_CPU0
  37  OCSET  BI  = VR_PVCCIN_CPU0_PH4_OCSET
  38  IOUT  OUT  = ISENSE_PVCCIN_CPU0_PH4_IMON
  39  REFIN  IN  = VR_PVCCIN_CPU0_AIREF4
  40  PGND(2)  GROUND  = GND
  41  GL(1)  BI  = TP_PVCCIN_CPU0_PH4_GL_1

EU4D2  NB3W1200L  IC  pkg LCC  page 102
  1  VDDA  POWER  = P3V3_DB1200_A
  2  GNDA  GROUND  = GND
  3  NC(0)  NC  = NC
  4  \100m_133m_n\  IN  = FM_100M_N
  5  HBW_BYPASS_LOBW_N  IN  = FM_HBW_BYPASS_LOWBW_N
  6  PWRGD_PWRDN_N  IN  = FM_DB1200_PWRGD_R
  7  GND(0)  GROUND  = GND
  8  VDDR  POWER  = P3V3_DB1200_R
  9  CLK_INP  IN  = CLK_100M_DB1200_DP
  10  CLK_INN  IN  = CLK_100M_DB1200_DN
  11  SA_0  IN  = FM_DB1200_SMB_SA0
  12  SDA  BI  = SMB_HOST_STBY_LVC3_SDA_R2
  13  SCL  BI  = SMB_HOST_STBY_LVC3_SCL_R2
  14  SA_1  IN  = FM_DB1200_SMB_SA1
  15  NC(2)  NC  = NC
  16  NC(1)  NC  = NC
  17  DIF_0P  OUT  = CLK_100M_CPU0_BCLK0_R_DP
  18  DIF_0N  OUT  = CLK_100M_CPU0_BCLK0_R_DN
  19  OE_0_N  IN  = FM_DB1200ZL_BCLKS_EN_N
  20  OE_1_N  IN  = FM_DB1200ZL_BCLKS_EN_N
  21  DIF_1P  OUT  = CLK_100M_CPU0_BCLK1_R_DP
  22  DIF_1N  OUT  = CLK_100M_CPU0_BCLK1_R_DN
  23  GND(1)  GROUND  = GND
  24  VDD(0)  POWER  = P3V3_DB1200
  25  VDDIO(0)  POWER  = P3V3_DB1200
  26  DIF_2P  OUT  = CLK_100M_CPU0_BCLK2_R_DP
  27  DIF_2N  OUT  = CLK_100M_CPU0_BCLK2_R_DN
  28  OE_2_N  IN  = FM_DB1200ZL_BCLKS_EN_N
  29  OE_3_N  IN  = FM_CPU0_MCP_CLK_EN_N
  30  DIF_3P  OUT  = CLK_100M_CPU0_PE_REFCLK_R_DP
  31  DIF_3N  OUT  = CLK_100M_CPU0_PE_REFCLK_R_DN
  32  VDDIO(1)  POWER  = P3V3_DB1200
  33  GND(2)  GROUND  = GND
  34  DIF_4P  OUT  = CLK_100M_CPU0_RC_REFCLK0_R_DP
  35  DIF_4N  OUT  = CLK_100M_CPU0_RC_REFCLK0_R_DN
  36  OE_4_N  IN  = FM_CPU0_MCP_CLK_EN_N
  37  OE_5_N  IN  = FM_CPU0_MCP_CLK_EN_N
  38  DIF_5P  OUT  = CLK_100M_CPU0_RC_REFCLK1_R_DP
  39  DIF_5N  OUT  = CLK_100M_CPU0_RC_REFCLK1_R_DN
  40  VDD(1)  POWER  = P3V3_DB1200
  41  GND(3)  GROUND  = GND
  42  DIF_6P  OUT  = CLK_100M_CPU1_BCLK0_R_DP
  43  DIF_6N  OUT  = CLK_100M_CPU1_BCLK0_R_DN
  44  OE_6_N  IN  = FM_DB1200ZL_BCLKS_EN_N
  45  OE_7_N  IN  = FM_DB1200ZL_BCLKS_EN_N
  46  DIF_7P  OUT  = CLK_100M_CPU1_BCLK1_R_DP
  47  DIF_7N  OUT  = CLK_100M_CPU1_BCLK1_R_DN
  48  GND(4)  GROUND  = GND
  49  VDDIO(2)  POWER  = P3V3_DB1200
  50  DIF_8P  OUT  = CLK_100M_CPU1_BCLK2_R_DP
  51  DIF_8N  OUT  = CLK_100M_CPU1_BCLK2_R_DN
  52  OE_8_N  IN  = FM_DB1200ZL_BCLKS_EN_N
  53  OE_9_N  IN  = FM_CPU1_MCP_CLK_EN_N
  54  DIF_9P  OUT  = CLK_100M_CPU1_PE_REFCLK_R_DP
  55  DIF_9N  OUT  = CLK_100M_CPU1_PE_REFCLK_R_DN
  56  VDDIO(3)  POWER  = P3V3_DB1200
  57  VDD(2)  POWER  = P3V3_DB1200
  58  GND(5)  GROUND  = GND
  59  DIF_10P  OUT  = CLK_100M_CPU1_RC_REFCLK0_R_DP
  60  DIF_10N  OUT  = CLK_100M_CPU1_RC_REFCLK0_R_DN
  61  OE_10_N  IN  = FM_CPU1_MCP_CLK_EN_N
  62  OE_11_N  IN  = FM_CPU1_MCP_CLK_EN_N
  63  DIF_11P  OUT  = CLK_100M_CPU1_RC_REFCLK1_R_DP
  64  DIF_11N  OUT  = CLK_100M_CPU1_RC_REFCLK1_R_DN
  65  THPAD  GROUND  = GND

EU4D3  IR354XX  IR35411 IC  pkg SM  page 203
  1  VOS  BI  = PVCCIN_CPU0
  2  LGND  GROUND  = GND
  3  VCC  POWER  = VR_PVCCIN_CPU0_PH3_VCIN
  4  VDRV  BI  = P5V_STBY
  5  PGND(0)  GROUND  = GND
  6  GL(0)  BI  = TP_PVCCIN_CPU0_PH3_GL_0
  7  PGND(1)  GROUND  = GND
  10  SW  BI  = VR_PVCCIN_CPU0_PHASE3
  25  VIN(0)  POWER  = VR_FET_SW_P12V_STBY_PVCCIN_CPU0
  30  VIN(1)  POWER  = VR_FET_SW_P12V_STBY_PVCCIN_CPU0
  31  NC  NC  = NC
  32  PHASE  BI  = VR_PVCCIN_CPU0_PH3_PHASE
  33  BOOST  BI  = VR_PVCCIN_CPU0_PH3_BOOT_R
  34  PWM  IN  = VR_PVCCIN_CPU0_PWM3
  35  EN  BI  = P5V_STBY
  36  TOUT_FLT  BI  = A_TSENSE_PVCCIN_CPU0
  37  OCSET  BI  = VR_PVCCIN_CPU0_PH3_OCSET
  38  IOUT  OUT  = ISENSE_PVCCIN_CPU0_PH3_IMON
  39  REFIN  IN  = VR_PVCCIN_CPU0_AIREF3
  40  PGND(2)  GROUND  = GND
  41  GL(1)  BI  = TP_PVCCIN_CPU0_PH3_GL_1

EU4D4  PXE1610B  IC  pkg QFN  page 201
  1  BPWM1  OUT  = VR_PVSA_CPU0_PWM
  2  APWM6  OUT  = NC
  3  APWM5  OUT  = VR_PVCCIN_CPU0_PWM5
  4  APWM4  OUT  = VR_PVCCIN_CPU0_PWM4
  5  APWM3  OUT  = VR_PVCCIN_CPU0_PWM3
  6  APWM2  OUT  = VR_PVCCIN_CPU0_PWM2
  7  APWM1  OUT  = VR_PVCCIN_CPU0_PWM1
  8  SDA  BI  = SMB_VR_STBY_LVC3_SDA
  9  SCL  BI  = SMB_VR_STBY_LVC3_SCL
  10  RESET_N  IN  = NC
  11  AVRRDY  OUT  = VR_VRRDY_PVCCIN_CPU0
  12  AVREN  IN  = VR_PVCCIN_CPU0_VREN
  13  VRHOT_N  OUT  = IRQ_PVCCIN_CPU0_VRHOT_LVC3_R_N
  14  PINALRT_N  OUT  = FM_PVCCIN_CPU0_PWR_IN_ALERT_N
  15  MP0  BI  = PWRGD_PVSA_CPU0_R
  16  MP1  BI  = NC
  17  VCLK  IN  = SVID_VCLK_PVCCIN_CPU0
  18  VDIO  BI  = SVID_VDIO_PVCCIN_CPU0
  19  VALRT_N  OUT  = SVID_VALERT_VCCIN_CPU0
  20  MP2  OUT  = PU_VR_PVCCIN_CPU0_FLT1_SMBALT_N
  21  AVSEN  IN  = VSENSE_PVCCIN_CPU0_AVSP
  22  AVREF  IN  = VSENSE_PVCCIN_CPU0_N
  23  AIREF1  IN  = VR_PVCCIN_CPU0_AIREF1
  24  AISEN1  IN  = ISENSE_PVCCIN_CPU0_PH1_IMON
  25  AIREF2  IN  = VR_PVCCIN_CPU0_AIREF2
  26  AISEN2  IN  = ISENSE_PVCCIN_CPU0_PH2_IMON
  27  AIREF3  IN  = VR_PVCCIN_CPU0_AIREF3
  28  AISEN3  IN  = ISENSE_PVCCIN_CPU0_PH3_IMON
  29  AIREF4  IN  = VR_PVCCIN_CPU0_AIREF4
  30  AISEN4  IN  = ISENSE_PVCCIN_CPU0_PH4_IMON
  31  AIREF5  IN  = VR_PVCCIN_CPU0_AIREF5
  32  AISEN5  IN  = ISENSE_PVCCIN_CPU0_PH5_IMON
  33  AIREF6  IN  = NC
  34  AISEN6  IN  = NC
  35  BVSEN  IN  = VSENSE_PVSA_CPU0_BVSP
  36  BVREF  IN  = VSENSE_PVSA_CPU0_N
  37  BIREF1  IN  = VR_PVSA_CPU0_BIREF1
  38  BISEN1  IN  = ISENSE_PVSA_CPU0_IMON
  39  MP3  OUT  = PU_VR_PVCCIN_CPU0_IMON
  40  MP4  OUT  = NC
  41  XADDR2  IN  = VR_PVCCIN_CPU0_XADDR2
  42  BTSEN  IN  = A_TSENSE_PVSA_CPU0
  43  ATSEN  IN  = A_TSENSE_PVCCIN_CPU0
  44  XADDR1  IN  = VR_PVCCIN_CPU0_XADDR1
  45  VINSEN  IN  = VR_PVCCIN_CPU0_AVINSEN
  46  IINSEN  IN  = NC
  47  VDD  POWER  = VR_PVCCIN_CPU0_VDD
  48  VD12  POWER  = VR_PVCCIN_CPU0_VD12
  49  THPAD  GROUND  = GND
